# T6G (Grand Teton) — schematic netlist excerpt (pin names and nets, part order shuffled) for the footprints in the layout excerpt that follows; sources: Cadence DE-HDL packaged netlist, KiCad conversion of 04192023_DAF0TMB3IC0_F0TG_MB_C_brd_V02_OCP.brd

C2612  Q_CAP  22UF 4V 20% X6S  pkg C0402  page 70 : A = PVDDIO_P0 ; B = GND
C6731  Q_CAP_DIFFBUS  DIFF BUS_0.22UF 6.3V 20% X6S  pkg C0201  page 352 : \1\ = P5E_CPU1_P3_TX_BUF_C_DP<3> ; \2\ = P5E_CPU1_P3_TX_BUF_DP<3>
R1549  Q_RES  33 5% CHIP  pkg 0402LF  page 81 : A = ESPI_CPU0_R1_D0 ; B = ESPI_CPU0_D0

(kicad_pcb
	(version 20260206)
	(generator "pcbnew")
	(generator_version "10.0")
	(general
		(thickness 1.6)
		(legacy_teardrops no)
	)
	(paper "A4")
	(title_block
		(title "04192023_DAF0TMB3IC0_F0TG_MB_C_brd_V02_OCP.brd")
		(comment 1 "Grand Teton / footprints 5295-5297 of 8354")
	)
	(layers
		(0 "F.Cu" signal "TOP")
		(4 "In1.Cu" signal "GND")
		(6 "In2.Cu" signal "IN1")
		(8 "In3.Cu" signal "GND1")
		(10 "In4.Cu" signal "IN2")
		(12 "In5.Cu" signal "GND2")
		(14 "In6.Cu" signal "IN3")
		(16 "In7.Cu" signal "GND3")
		(18 "In8.Cu" signal "VCC")
		(20 "In9.Cu" signal "VCC1")
		(22 "In10.Cu" signal "GND4")
		(24 "In11.Cu" signal "IN4")
		(26 "In12.Cu" signal "GND5")
		(28 "In13.Cu" signal "IN5")
		(30 "In14.Cu" signal "GND6")
		(32 "In15.Cu" signal "IN6")
		(34 "In16.Cu" signal "GND7")
		(2 "B.Cu" signal "BOTTOM")
		(9 "F.Adhes" user "F.Adhesive")
		(11 "B.Adhes" user "B.Adhesive")
		(13 "F.Paste" user "Package Geometry/Pastemask Top")
		(15 "B.Paste" user "Package Geometry/Pastemask Bottom")
		(5 "F.SilkS" user "Ref Des/Silkscreen Top")
		(7 "B.SilkS" user "Ref Des/Silkscreen Bottom")
		(1 "F.Mask" user "Board Geometry/Soldermask Top")
		(3 "B.Mask" user "Board Geometry/Soldermask Bottom")
		(17 "Dwgs.User" user "User.Drawings")
		(19 "Cmts.User" user "User.Comments")
		(21 "Eco1.User" user "User.Eco1")
		(23 "Eco2.User" user "User.Eco2")
		(25 "Edge.Cuts" user "Board Geometry/Outline")
		(27 "Margin" user)
		(31 "F.CrtYd" user "Package Geometry/Place Bound Top")
		(29 "B.CrtYd" user "Package Geometry/Place Bound Bottom")
		(35 "F.Fab" user "Ref Des/Assembly Top")
		(33 "B.Fab" user "Ref Des/Assembly Bottom")
	)
	(footprint ""
		(layer "B.Cu")
		(at 346.373958 -265.045952)
		(property "Reference" "C2612"
			(at 0 0 0)
			(layer "B.SilkS")
			(hide yes)
			(effects
				(font
					(size 1.27 1.27)
				)
				(justify mirror)
			)
		)
		(property "Value" ""
			(at 0 0 0)
			(layer "B.Fab")
			(effects
				(font
					(size 1.27 1.27)
				)
				(justify mirror)
			)
		)
		(duplicate_pad_numbers_are_jumpers no)
		(fp_line
			(start -0.7874 -0.4064)
			(end -0.7874 0.4064)
			(stroke
				(width 0.1524)
				(type default)
			)
			(layer "B.SilkS")
		)
		(fp_line
			(start -0.7874 0.4064)
			(end 0.7874 0.4064)
			(stroke
				(width 0.1524)
				(type default)
			)
			(layer "B.SilkS")
		)
		(fp_line
			(start 0.7874 -0.4064)
			(end -0.7874 -0.4064)
			(stroke
				(width 0.1524)
				(type default)
			)
			(layer "B.SilkS")
		)
		(fp_line
			(start 0.7874 0.4064)
			(end 0.7874 -0.4064)
			(stroke
				(width 0.1524)
				(type default)
			)
			(layer "B.SilkS")
		)
		(fp_line
			(start -0.67945 -0.3048)
			(end -0.67945 0.3048)
			(stroke
				(width 0.1)
				(type default)
			)
			(layer "B.Fab")
		)
		(fp_line
			(start -0.67945 0.3048)
			(end -0.120396 0.3048)
			(stroke
				(width 0.1)
				(type default)
			)
			(layer "B.Fab")
		)
		(fp_line
			(start -0.12065 -0.3048)
			(end -0.67945 -0.3048)
			(stroke
				(width 0.1)
				(type default)
			)
			(layer "B.Fab")
		)
		(fp_line
			(start -0.12065 -0.2794)
			(end -0.12065 -0.3048)
			(stroke
				(width 0.1)
				(type default)
			)
			(layer "B.Fab")
		)
		(fp_line
			(start -0.120396 0.2794)
			(end 0.12065 0.2794)
			(stroke
				(width 0.1)
				(type default)
			)
			(layer "B.Fab")
		)
		(fp_line
			(start -0.120396 0.3048)
			(end -0.120396 0.2794)
			(stroke
				(width 0.1)
				(type default)
			)
			(layer "B.Fab")
		)
		(fp_line
			(start 0.12065 -0.305054)
			(end 0.12065 -0.2794)
			(stroke
				(width 0.1)
				(type default)
			)
			(layer "B.Fab")
		)
		(fp_line
			(start 0.12065 -0.2794)
			(end -0.12065 -0.2794)
			(stroke
				(width 0.1)
				(type default)
			)
			(layer "B.Fab")
		)
		(fp_line
			(start 0.12065 0.2794)
			(end 0.12065 0.3048)
			(stroke
				(width 0.1)
				(type default)
			)
			(layer "B.Fab")
		)
		(fp_line
			(start 0.12065 0.3048)
			(end 0.67945 0.3048)
			(stroke
				(width 0.1)
				(type default)
			)
			(layer "B.Fab")
		)
		(fp_line
			(start 0.67945 -0.305054)
			(end 0.12065 -0.305054)
			(stroke
				(width 0.1)
				(type default)
			)
			(layer "B.Fab")
		)
		(fp_line
			(start 0.67945 0.3048)
			(end 0.67945 -0.305054)
			(stroke
				(width 0.1)
				(type default)
			)
			(layer "B.Fab")
		)
		(pad "1" smd circle
			(at 0.40005 0 180)
			(size 0 0)
			(layers "B.Cu" "B.Mask" "B.Paste")
			(net "PVDDIO_P0")
		)
		(pad "2" smd circle
			(at -0.40005 0 180)
			(size 0 0)
			(layers "B.Cu" "B.Mask" "B.Paste")
			(net "GND")
		)
	)
	(footprint ""
		(layer "B.Cu")
		(at 126.504446 -408.517344 90)
		(property "Reference" "C6731"
			(at 0 0 90)
			(layer "B.SilkS")
			(hide yes)
			(effects
				(font
					(size 1.27 1.27)
				)
				(justify mirror)
			)
		)
		(property "Value" ""
			(at 0 0 90)
			(layer "B.Fab")
			(effects
				(font
					(size 1.27 1.27)
				)
				(justify mirror)
			)
		)
		(duplicate_pad_numbers_are_jumpers no)
		(fp_line
			(start 0.299974 -0.150114)
			(end -0.299974 -0.150114)
			(stroke
				(width 0.1)
				(type default)
			)
			(layer "B.Fab")
		)
		(fp_line
			(start -0.299974 -0.150114)
			(end -0.299974 0.150114)
			(stroke
				(width 0.1)
				(type default)
			)
			(layer "B.Fab")
		)
		(fp_line
			(start 0.299974 0.150114)
			(end 0.299974 -0.150114)
			(stroke
				(width 0.1)
				(type default)
			)
			(layer "B.Fab")
		)
		(fp_line
			(start -0.299974 0.150114)
			(end 0.299974 0.150114)
			(stroke
				(width 0.1)
				(type default)
			)
			(layer "B.Fab")
		)
		(pad "1" smd rect
			(at 0.2667 0 270)
			(size 0.3048 0.381)
			(layers "B.Cu" "B.Mask" "B.Paste")
			(net "P5E_CPU1_P3_TX_BUF_C_DP<3>")
		)
		(pad "2" smd rect
			(at -0.2667 0 270)
			(size 0.3048 0.381)
			(layers "B.Cu" "B.Mask" "B.Paste")
			(net "P5E_CPU1_P3_TX_BUF_DP<3>")
		)
	)
	(footprint ""
		(layer "B.Cu")
		(at 195.390008 -126.833376 180)
		(property "Reference" "R1549"
			(at 0 0 0)
			(layer "B.SilkS")
			(hide yes)
			(effects
				(font
					(size 1.27 1.27)
				)
				(justify mirror)
			)
		)
		(property "Value" ""
			(at 0 0 0)
			(layer "B.Fab")
			(effects
				(font
					(size 1.27 1.27)
				)
				(justify mirror)
			)
		)
		(duplicate_pad_numbers_are_jumpers no)
		(fp_line
			(start 0.7874 0.4064)
			(end 0.7874 -0.4064)
			(stroke
				(width 0.1524)
				(type default)
			)
			(layer "B.SilkS")
		)
		(fp_line
			(start 0.7874 -0.4064)
			(end -0.7874 -0.4064)
			(stroke
				(width 0.1524)
				(type default)
			)
			(layer "B.SilkS")
		)
		(fp_line
			(start -0.7874 0.4064)
			(end 0.7874 0.4064)
			(stroke
				(width 0.1524)
				(type default)
			)
			(layer "B.SilkS")
		)
		(fp_line
			(start -0.7874 -0.4064)
			(end -0.7874 0.4064)
			(stroke
				(width 0.1524)
				(type default)
			)
			(layer "B.SilkS")
		)
		(fp_line
			(start 0.67945 0.3048)
			(end 0.67945 -0.305054)
			(stroke
				(width 0.1)
				(type default)
			)
			(layer "B.Fab")
		)
		(fp_line
			(start 0.67945 -0.305054)
			(end 0.12065 -0.305054)
			(stroke
				(width 0.1)
				(type default)
			)
			(layer "B.Fab")
		)
		(fp_line
			(start 0.12065 0.3048)
			(end 0.67945 0.3048)
			(stroke
				(width 0.1)
				(type default)
			)
			(layer "B.Fab")
		)
		(fp_line
			(start 0.12065 0.2794)
			(end 0.12065 0.3048)
			(stroke
				(width 0.1)
				(type default)
			)
			(layer "B.Fab")
		)
		(fp_line
			(start 0.12065 -0.2794)
			(end -0.12065 -0.2794)
			(stroke
				(width 0.1)
				(type default)
			)
			(layer "B.Fab")
		)
		(fp_line
			(start 0.12065 -0.305054)
			(end 0.12065 -0.2794)
			(stroke
				(width 0.1)
				(type default)
			)
			(layer "B.Fab")
		)
		(fp_line
			(start -0.120396 0.3048)
			(end -0.120396 0.2794)
			(stroke
				(width 0.1)
				(type default)
			)
			(layer "B.Fab")
		)
		(fp_line
			(start -0.120396 0.2794)
			(end 0.12065 0.2794)
			(stroke
				(width 0.1)
				(type default)
			)
			(layer "B.Fab")
		)
		(fp_line
			(start -0.12065 -0.2794)
			(end -0.12065 -0.3048)
			(stroke
				(width 0.1)
				(type default)
			)
			(layer "B.Fab")
		)
		(fp_line
			(start -0.12065 -0.3048)
			(end -0.67945 -0.3048)
			(stroke
				(width 0.1)
				(type default)
			)
			(layer "B.Fab")
		)
		(fp_line
			(start -0.67945 0.3048)
			(end -0.120396 0.3048)
			(stroke
				(width 0.1)
				(type default)
			)
			(layer "B.Fab")
		)
		(fp_line
			(start -0.67945 -0.3048)
			(end -0.67945 0.3048)
			(stroke
				(width 0.1)
				(type default)
			)
			(layer "B.Fab")
		)
		(pad "1" smd circle
			(at 0.40005 0)
			(size 0 0)
			(layers "B.Cu" "B.Mask" "B.Paste")
			(net "ESPI_CPU0_R1_D0")
		)
		(pad "2" smd circle
			(at -0.40005 0)
			(size 0 0)
			(layers "B.Cu" "B.Mask" "B.Paste")
			(net "ESPI_CPU0_D0")
		)
	)
)
